# T6G (Grand Teton) — schematic netlist excerpt (pin names and nets, part order shuffled) for the footprints in the layout excerpt that follows; sources: Cadence DE-HDL packaged netlist, KiCad conversion of 04192023_DAF0TMB3IC0_F0TG_MB_C_brd_V02_OCP.brd

R1094  Q_RES  0 5% EMPTY  pkg 0603LF  page 312 : A = P0V9_CPU0_RT_2D ; B = P0V9_CPU0_RT3_2A_2D
R400  Q_RES  1K 1% CHIP  pkg 0402LF  page 27 : A = PVDD18_S5_P0 ; B = JTAG_CPU0_TRST_N

(kicad_pcb
	(version 20260206)
	(generator "pcbnew")
	(generator_version "10.0")
	(general
		(thickness 1.6)
		(legacy_teardrops no)
	)
	(paper "A4")
	(title_block
		(title "04192023_DAF0TMB3IC0_F0TG_MB_C_brd_V02_OCP.brd")
		(comment 1 "Grand Teton / footprints 5791-5792 of 8354")
	)
	(layers
		(0 "F.Cu" signal "TOP")
		(4 "In1.Cu" signal "GND")
		(6 "In2.Cu" signal "IN1")
		(8 "In3.Cu" signal "GND1")
		(10 "In4.Cu" signal "IN2")
		(12 "In5.Cu" signal "GND2")
		(14 "In6.Cu" signal "IN3")
		(16 "In7.Cu" signal "GND3")
		(18 "In8.Cu" signal "VCC")
		(20 "In9.Cu" signal "VCC1")
		(22 "In10.Cu" signal "GND4")
		(24 "In11.Cu" signal "IN4")
		(26 "In12.Cu" signal "GND5")
		(28 "In13.Cu" signal "IN5")
		(30 "In14.Cu" signal "GND6")
		(32 "In15.Cu" signal "IN6")
		(34 "In16.Cu" signal "GND7")
		(2 "B.Cu" signal "BOTTOM")
		(9 "F.Adhes" user "F.Adhesive")
		(11 "B.Adhes" user "B.Adhesive")
		(13 "F.Paste" user "Package Geometry/Pastemask Top")
		(15 "B.Paste" user "Package Geometry/Pastemask Bottom")
		(5 "F.SilkS" user "Ref Des/Silkscreen Top")
		(7 "B.SilkS" user "Ref Des/Silkscreen Bottom")
		(1 "F.Mask" user "Board Geometry/Soldermask Top")
		(3 "B.Mask" user "Board Geometry/Soldermask Bottom")
		(17 "Dwgs.User" user "User.Drawings")
		(19 "Cmts.User" user "User.Comments")
		(21 "Eco1.User" user "User.Eco1")
		(23 "Eco2.User" user "User.Eco2")
		(25 "Edge.Cuts" user "Board Geometry/Outline")
		(27 "Margin" user)
		(31 "F.CrtYd" user "Package Geometry/Place Bound Top")
		(29 "B.CrtYd" user "Package Geometry/Place Bound Bottom")
		(35 "F.Fab" user "Ref Des/Assembly Top")
		(33 "B.Fab" user "Ref Des/Assembly Bottom")
	)
	(footprint ""
		(layer "B.Cu")
		(at 374.440958 -208.530952 -90)
		(property "Reference" "R400"
			(at 0 0 90)
			(layer "B.SilkS")
			(hide yes)
			(effects
				(font
					(size 1.27 1.27)
				)
				(justify mirror)
			)
		)
		(property "Value" ""
			(at 0 0 90)
			(layer "B.Fab")
			(effects
				(font
					(size 1.27 1.27)
				)
				(justify mirror)
			)
		)
		(duplicate_pad_numbers_are_jumpers no)
		(fp_line
			(start -0.7874 0.4064)
			(end 0.7874 0.4064)
			(stroke
				(width 0.1524)
				(type default)
			)
			(layer "B.SilkS")
		)
		(fp_line
			(start 0.7874 0.4064)
			(end 0.7874 -0.4064)
			(stroke
				(width 0.1524)
				(type default)
			)
			(layer "B.SilkS")
		)
		(fp_line
			(start -0.7874 -0.4064)
			(end -0.7874 0.4064)
			(stroke
				(width 0.1524)
				(type default)
			)
			(layer "B.SilkS")
		)
		(fp_line
			(start 0.7874 -0.4064)
			(end -0.7874 -0.4064)
			(stroke
				(width 0.1524)
				(type default)
			)
			(layer "B.SilkS")
		)
		(fp_line
			(start -0.67945 0.3048)
			(end -0.120396 0.3048)
			(stroke
				(width 0.1)
				(type default)
			)
			(layer "B.Fab")
		)
		(fp_line
			(start -0.120396 0.3048)
			(end -0.120396 0.2794)
			(stroke
				(width 0.1)
				(type default)
			)
			(layer "B.Fab")
		)
		(fp_line
			(start 0.12065 0.3048)
			(end 0.67945 0.3048)
			(stroke
				(width 0.1)
				(type default)
			)
			(layer "B.Fab")
		)
		(fp_line
			(start 0.67945 0.3048)
			(end 0.67945 -0.305054)
			(stroke
				(width 0.1)
				(type default)
			)
			(layer "B.Fab")
		)
		(fp_line
			(start -0.120396 0.2794)
			(end 0.12065 0.2794)
			(stroke
				(width 0.1)
				(type default)
			)
			(layer "B.Fab")
		)
		(fp_line
			(start 0.12065 0.2794)
			(end 0.12065 0.3048)
			(stroke
				(width 0.1)
				(type default)
			)
			(layer "B.Fab")
		)
		(fp_line
			(start -0.12065 -0.2794)
			(end -0.12065 -0.3048)
			(stroke
				(width 0.1)
				(type default)
			)
			(layer "B.Fab")
		)
		(fp_line
			(start 0.12065 -0.2794)
			(end -0.12065 -0.2794)
			(stroke
				(width 0.1)
				(type default)
			)
			(layer "B.Fab")
		)
		(fp_line
			(start -0.67945 -0.3048)
			(end -0.67945 0.3048)
			(stroke
				(width 0.1)
				(type default)
			)
			(layer "B.Fab")
		)
		(fp_line
			(start -0.12065 -0.3048)
			(end -0.67945 -0.3048)
			(stroke
				(width 0.1)
				(type default)
			)
			(layer "B.Fab")
		)
		(fp_line
			(start 0.12065 -0.305054)
			(end 0.12065 -0.2794)
			(stroke
				(width 0.1)
				(type default)
			)
			(layer "B.Fab")
		)
		(fp_line
			(start 0.67945 -0.305054)
			(end 0.12065 -0.305054)
			(stroke
				(width 0.1)
				(type default)
			)
			(layer "B.Fab")
		)
		(pad "1" smd circle
			(at 0.40005 0 90)
			(size 0 0)
			(layers "B.Cu" "B.Mask" "B.Paste")
			(net "PVDD18_S5_P0")
		)
		(pad "2" smd circle
			(at -0.40005 0 90)
			(size 0 0)
			(layers "B.Cu" "B.Mask" "B.Paste")
			(net "JTAG_CPU0_TRST_N")
		)
	)
	(footprint ""
		(layer "B.Cu")
		(at 362.988606 -401.624546 180)
		(property "Reference" "R1094"
			(at 0 0 0)
			(layer "B.SilkS")
			(hide yes)
			(effects
				(font
					(size 1.27 1.27)
				)
				(justify mirror)
			)
		)
		(property "Value" ""
			(at 0 0 0)
			(layer "B.Fab")
			(effects
				(font
					(size 1.27 1.27)
				)
				(justify mirror)
			)
		)
		(duplicate_pad_numbers_are_jumpers no)
		(fp_line
			(start 1.2954 0.5842)
			(end 1.2954 -0.5842)
			(stroke
				(width 0.1524)
				(type default)
			)
			(layer "B.SilkS")
		)
		(fp_line
			(start 1.2954 -0.5842)
			(end -1.2954 -0.5842)
			(stroke
				(width 0.1524)
				(type default)
			)
			(layer "B.SilkS")
		)
		(fp_line
			(start -1.2954 0.5842)
			(end 1.2954 0.5842)
			(stroke
				(width 0.1524)
				(type default)
			)
			(layer "B.SilkS")
		)
		(fp_line
			(start -1.2954 -0.5842)
			(end -1.2954 0.5842)
			(stroke
				(width 0.1524)
				(type default)
			)
			(layer "B.SilkS")
		)
		(fp_line
			(start 1.1938 0.4064)
			(end 1.1938 -0.406654)
			(stroke
				(width 0.1)
				(type default)
			)
			(layer "B.Fab")
		)
		(fp_line
			(start 1.1938 -0.406654)
			(end 0.8636 -0.406654)
			(stroke
				(width 0.1)
				(type default)
			)
			(layer "B.Fab")
		)
		(fp_line
			(start 0.8636 0.4572)
			(end 0.8636 0.4318)
			(stroke
				(width 0.1)
				(type default)
			)
			(layer "B.Fab")
		)
		(fp_line
			(start 0.8636 0.4318)
			(end 0.8636 0.4064)
			(stroke
				(width 0.1)
				(type default)
			)
			(layer "B.Fab")
		)
		(fp_line
			(start 0.8636 0.4064)
			(end 1.1938 0.4064)
			(stroke
				(width 0.1)
				(type default)
			)
			(layer "B.Fab")
		)
		(fp_line
			(start 0.8636 -0.406654)
			(end 0.8636 -0.4572)
			(stroke
				(width 0.1)
				(type default)
			)
			(layer "B.Fab")
		)
		(fp_line
			(start 0.8636 -0.4572)
			(end -0.8636 -0.4572)
			(stroke
				(width 0.1)
				(type default)
			)
			(layer "B.Fab")
		)
		(fp_line
			(start -0.8636 0.4572)
			(end 0.8636 0.4572)
			(stroke
				(width 0.1)
				(type default)
			)
			(layer "B.Fab")
		)
		(fp_line
			(start -0.8636 0.4064)
			(end -0.8636 0.4572)
			(stroke
				(width 0.1)
				(type default)
			)
			(layer "B.Fab")
		)
		(fp_line
			(start -0.8636 -0.406654)
			(end -1.1938 -0.406654)
			(stroke
				(width 0.1)
				(type default)
			)
			(layer "B.Fab")
		)
		(fp_line
			(start -0.8636 -0.4572)
			(end -0.8636 -0.406654)
			(stroke
				(width 0.1)
				(type default)
			)
			(layer "B.Fab")
		)
		(fp_line
			(start -1.1938 0.4064)
			(end -0.8636 0.4064)
			(stroke
				(width 0.1)
				(type default)
			)
			(layer "B.Fab")
		)
		(fp_line
			(start -1.1938 -0.406654)
			(end -1.1938 0.4064)
			(stroke
				(width 0.1)
				(type default)
			)
			(layer "B.Fab")
		)
		(pad "1" smd rect
			(at 0.7366 0 90)
			(size 0.7112 0.8128)
			(layers "B.Cu" "B.Mask" "B.Paste")
			(net "P0V9_CPU0_RT_2D")
		)
		(pad "2" smd rect
			(at -0.7366 0 90)
			(size 0.7112 0.8128)
			(layers "B.Cu" "B.Mask" "B.Paste")
			(net "P0V9_CPU0_RT3_2A_2D")
		)
	)
)
